(kicad_pcb
	(version 20241229)
	(generator "pcbnew")
	(generator_version "9.0")
	(general
		(thickness 1.599998)
		(legacy_teardrops no)
	)
	(paper "A4")
	(title_block
		(date "2023-02-12")
		(rev "1.1.5")
		(comment 9 "footprints 436-442 of 473")
	)
	(layers
		(0 "F.Cu" signal)
		(4 "In1.Cu" power "In1.GND")
		(6 "In2.Cu" signal)
		(8 "In3.Cu" power "In3.GND")
		(10 "In4.Cu" power "In4.VCC")
		(12 "In5.Cu" signal)
		(14 "In6.Cu" power "In6.VCC")
		(2 "B.Cu" signal)
		(9 "F.Adhes" user "F.Adhesive")
		(11 "B.Adhes" user "B.Adhesive")
		(13 "F.Paste" user)
		(15 "B.Paste" user)
		(5 "F.SilkS" user "F.Silkscreen")
		(7 "B.SilkS" user "B.Silkscreen")
		(1 "F.Mask" user)
		(3 "B.Mask" user)
		(17 "Dwgs.User" user "User.Drawings")
		(19 "Cmts.User" user "User.Comments")
		(21 "Eco1.User" user "User.Eco1")
		(23 "Eco2.User" user "User.Eco2")
		(25 "Edge.Cuts" user)
		(27 "Margin" user)
		(31 "F.CrtYd" user "F.Courtyard")
		(29 "B.CrtYd" user "B.Courtyard")
		(35 "F.Fab" user)
		(33 "B.Fab" user)
	)
	(footprint "antmicro-footprints:R_0603_1608Metric"
		(layer "B.Cu")
		(at 170.536328 86.697157 180)
		(descr "Resistor SMD 0603")
		(tags "resistor SMD 0603")
		(property "Reference" "R3"
			(at -0.763672 0.597157 0)
			(layer "B.SilkS")
			(effects
				(font
					(size 0.7 0.7)
					(thickness 0.15)
				)
				(justify left bottom mirror)
			)
		)
		(property "Value" "R_120R_0603"
			(at 0 -1.6 0)
			(layer "B.Fab")
			(effects
				(font
					(size 0.7 0.7)
					(thickness 0.15)
				)
				(justify left bottom mirror)
			)
		)
		(property "Description" "120R resistor in 0603 package with 1% tolerance"
			(at 0 0 180)
			(layer "F.Fab")
			(hide yes)
			(effects
				(font
					(size 1.27 1.27)
					(thickness 0.15)
				)
			)
		)
		(property "Author" "Antmicro"
			(at 341.072656 173.394314 0)
			(layer "B.Fab")
			(hide yes)
			(effects
				(font
					(size 1 1)
					(thickness 0.15)
				)
				(justify mirror)
			)
		)
		(property "License" "Apache-2.0"
			(at 341.072656 173.394314 0)
			(layer "B.Fab")
			(hide yes)
			(effects
				(font
					(size 1 1)
					(thickness 0.15)
				)
				(justify mirror)
			)
		)
		(property "MPN" "CR0603-FX-1200ELF"
			(at 341.072656 173.394314 0)
			(layer "B.Fab")
			(hide yes)
			(effects
				(font
					(size 1 1)
					(thickness 0.15)
				)
				(justify mirror)
			)
		)
		(property "Manufacturer" "Bourns"
			(at 341.072656 173.394314 0)
			(layer "B.Fab")
			(hide yes)
			(effects
				(font
					(size 1 1)
					(thickness 0.15)
				)
				(justify mirror)
			)
		)
		(property "Tolerance" "1%"
			(at 341.072656 173.394314 0)
			(layer "B.Fab")
			(hide yes)
			(effects
				(font
					(size 1 1)
					(thickness 0.15)
				)
				(justify mirror)
			)
		)
		(property "Val" "120R"
			(at 341.072656 173.394314 0)
			(layer "B.Fab")
			(hide yes)
			(effects
				(font
					(size 1 1)
					(thickness 0.15)
				)
				(justify mirror)
			)
		)
		(sheetname "FPGA Banks")
		(sheetfile "fpga-banks.kicad_sch")
		(attr smd)
		(fp_line
			(start -0.3 0.3)
			(end 0.3 0.3)
			(stroke
				(width 0.15)
				(type solid)
			)
			(layer "B.SilkS")
		)
		(fp_line
			(start -0.3 -0.3)
			(end 0.3 -0.3)
			(stroke
				(width 0.15)
				(type solid)
			)
			(layer "B.SilkS")
		)
		(fp_rect
			(start -1.25 0.7)
			(end 1.25 -0.7)
			(stroke
				(width 0.05)
				(type solid)
			)
			(fill no)
			(layer "B.CrtYd")
		)
		(fp_rect
			(start -0.8 0.4)
			(end 0.8 -0.4)
			(stroke
				(width 0.15)
				(type solid)
			)
			(fill no)
			(layer "B.Fab")
		)
		(pad "1" smd roundrect
			(at -0.7 0 180)
			(size 0.6 0.8)
			(layers "B.Cu" "B.Mask" "B.Paste")
			(roundrect_rratio 0.2)
			(net 511 "VRN")
			(pintype "passive")
		)
		(pad "2" smd roundrect
			(at 0.7 0 180)
			(size 0.6 0.8)
			(layers "B.Cu" "B.Mask" "B.Paste")
			(roundrect_rratio 0.2)
			(net 66 "VDDQ")
			(pintype "passive")
		)
	)
	(footprint "antmicro-footprints:R_0603_1608Metric"
		(layer "B.Cu")
		(at 162.836328 89.897157)
		(descr "Resistor SMD 0603")
		(tags "resistor SMD 0603")
		(property "Reference" "R4"
			(at 0.663672 -0.597157 180)
			(layer "B.SilkS")
			(effects
				(font
					(size 0.7 0.7)
					(thickness 0.15)
				)
				(justify left bottom mirror)
			)
		)
		(property "Value" "R_120R_0603"
			(at 0 -1.6 180)
			(layer "B.Fab")
			(effects
				(font
					(size 0.7 0.7)
					(thickness 0.15)
				)
				(justify left bottom mirror)
			)
		)
		(property "Description" "120R resistor in 0603 package with 1% tolerance"
			(at 0 0 0)
			(layer "F.Fab")
			(hide yes)
			(effects
				(font
					(size 1.27 1.27)
					(thickness 0.15)
				)
			)
		)
		(property "Author" "Antmicro"
			(at 0 0 0)
			(layer "B.Fab")
			(hide yes)
			(effects
				(font
					(size 1 1)
					(thickness 0.15)
				)
				(justify mirror)
			)
		)
		(property "License" "Apache-2.0"
			(at 0 0 0)
			(layer "B.Fab")
			(hide yes)
			(effects
				(font
					(size 1 1)
					(thickness 0.15)
				)
				(justify mirror)
			)
		)
		(property "MPN" "CR0603-FX-1200ELF"
			(at 0 0 0)
			(layer "B.Fab")
			(hide yes)
			(effects
				(font
					(size 1 1)
					(thickness 0.15)
				)
				(justify mirror)
			)
		)
		(property "Manufacturer" "Bourns"
			(at 0 0 0)
			(layer "B.Fab")
			(hide yes)
			(effects
				(font
					(size 1 1)
					(thickness 0.15)
				)
				(justify mirror)
			)
		)
		(property "Tolerance" "1%"
			(at 0 0 0)
			(layer "B.Fab")
			(hide yes)
			(effects
				(font
					(size 1 1)
					(thickness 0.15)
				)
				(justify mirror)
			)
		)
		(property "Val" "120R"
			(at 0 0 0)
			(layer "B.Fab")
			(hide yes)
			(effects
				(font
					(size 1 1)
					(thickness 0.15)
				)
				(justify mirror)
			)
		)
		(sheetname "FPGA Banks")
		(sheetfile "fpga-banks.kicad_sch")
		(attr smd)
		(fp_line
			(start -0.3 -0.3)
			(end 0.3 -0.3)
			(stroke
				(width 0.15)
				(type solid)
			)
			(layer "B.SilkS")
		)
		(fp_line
			(start -0.3 0.3)
			(end 0.3 0.3)
			(stroke
				(width 0.15)
				(type solid)
			)
			(layer "B.SilkS")
		)
		(fp_rect
			(start -1.25 0.7)
			(end 1.25 -0.7)
			(stroke
				(width 0.05)
				(type solid)
			)
			(fill no)
			(layer "B.CrtYd")
		)
		(fp_rect
			(start -0.8 0.4)
			(end 0.8 -0.4)
			(stroke
				(width 0.15)
				(type solid)
			)
			(fill no)
			(layer "B.Fab")
		)
		(pad "1" smd roundrect
			(at -0.7 0)
			(size 0.6 0.8)
			(layers "B.Cu" "B.Mask" "B.Paste")
			(roundrect_rratio 0.2)
			(net 512 "VRP")
			(pintype "passive")
		)
		(pad "2" smd roundrect
			(at 0.7 0)
			(size 0.6 0.8)
			(layers "B.Cu" "B.Mask" "B.Paste")
			(roundrect_rratio 0.2)
			(net 5 "GND")
			(pintype "passive")
		)
	)
	(footprint "antmicro-footprints:C_0402_1005Metric"
		(layer "B.Cu")
		(at 197.486328 100.020008 -90)
		(descr "Capacitor SMD 0402")
		(tags "capacitor SMD 0402")
		(property "Reference" "C101"
			(at -1.820008 -6.613672 90)
			(layer "B.SilkS")
			(effects
				(font
					(size 0.7 0.7)
					(thickness 0.15)
				)
				(justify left bottom mirror)
			)
		)
		(property "Value" "C_4u7_0402"
			(at 0 -1.4 90)
			(layer "B.Fab")
			(effects
				(font
					(size 0.7 0.7)
					(thickness 0.15)
				)
				(justify left bottom mirror)
			)
		)
		(property "Description" " "
			(at 0 0 270)
			(layer "F.Fab")
			(hide yes)
			(effects
				(font
					(size 1.27 1.27)
					(thickness 0.15)
				)
			)
		)
		(property "Author" "Antmicro"
			(at 97.46632 297.506336 0)
			(layer "B.Fab")
			(hide yes)
			(effects
				(font
					(size 1 1)
					(thickness 0.15)
				)
				(justify mirror)
			)
		)
		(property "Dielectric" ""
			(at 97.46632 297.506336 0)
			(layer "B.Fab")
			(hide yes)
			(effects
				(font
					(size 1 1)
					(thickness 0.15)
				)
				(justify mirror)
			)
		)
		(property "License" "Apache-2.0"
			(at 97.46632 297.506336 0)
			(layer "B.Fab")
			(hide yes)
			(effects
				(font
					(size 1 1)
					(thickness 0.15)
				)
				(justify mirror)
			)
		)
		(property "MPN" "GRM155R61A475MEAAD"
			(at 97.46632 297.506336 0)
			(layer "B.Fab")
			(hide yes)
			(effects
				(font
					(size 1 1)
					(thickness 0.15)
				)
				(justify mirror)
			)
		)
		(property "Manufacturer" "Murata"
			(at 97.46632 297.506336 0)
			(layer "B.Fab")
			(hide yes)
			(effects
				(font
					(size 1 1)
					(thickness 0.15)
				)
				(justify mirror)
			)
		)
		(property "Val" "4u7"
			(at 97.46632 297.506336 0)
			(layer "B.Fab")
			(hide yes)
			(effects
				(font
					(size 1 1)
					(thickness 0.15)
				)
				(justify mirror)
			)
		)
		(property "Voltage" ""
			(at 97.46632 297.506336 0)
			(layer "B.Fab")
			(hide yes)
			(effects
				(font
					(size 1 1)
					(thickness 0.15)
				)
				(justify mirror)
			)
		)
		(sheetname "Ethernet")
		(sheetfile "ethernet.kicad_sch")
		(attr smd)
		(fp_rect
			(start -0.94 0.47)
			(end 0.94 -0.47)
			(stroke
				(width 0.05)
				(type solid)
			)
			(fill no)
			(layer "B.CrtYd")
		)
		(fp_rect
			(start -0.499 0.249)
			(end 0.499 -0.249)
			(stroke
				(width 0.15)
				(type solid)
			)
			(fill no)
			(layer "B.Fab")
		)
		(pad "1" smd roundrect
			(at -0.484 0 270)
			(size 0.59 0.64)
			(layers "B.Cu" "B.Mask" "B.Paste")
			(roundrect_rratio 0.25)
			(net 459 "3V3_SYS")
			(pintype "passive")
		)
		(pad "2" smd roundrect
			(at 0.484 0 270)
			(size 0.59 0.64)
			(layers "B.Cu" "B.Mask" "B.Paste")
			(roundrect_rratio 0.25)
			(net 5 "GND")
			(pintype "passive")
		)
	)
	(footprint "antmicro-footprints:R_0402_1005Metric"
		(layer "B.Cu")
		(at 208.786328 103.520008)
		(descr "Resistor SMD 0402")
		(tags "resistor SMD 0402")
		(property "Reference" "R82"
			(at 3.013672 0.379992 180)
			(layer "B.SilkS")
			(effects
				(font
					(size 0.7 0.7)
					(thickness 0.15)
				)
				(justify left bottom mirror)
			)
		)
		(property "Value" "R_10k2_0402"
			(at 0 -1.4 180)
			(layer "B.Fab")
			(effects
				(font
					(size 0.7 0.7)
					(thickness 0.15)
				)
				(justify left bottom mirror)
			)
		)
		(property "Description" "10k2 resistor in 0402 package with 1% tolerance"
			(at 0 0 0)
			(layer "F.Fab")
			(hide yes)
			(effects
				(font
					(size 1.27 1.27)
					(thickness 0.15)
				)
			)
		)
		(property "Author" "Antmicro"
			(at 0 0 0)
			(layer "B.Fab")
			(hide yes)
			(effects
				(font
					(size 1 1)
					(thickness 0.15)
				)
				(justify mirror)
			)
		)
		(property "License" "Apache-2.0"
			(at 0 0 0)
			(layer "B.Fab")
			(hide yes)
			(effects
				(font
					(size 1 1)
					(thickness 0.15)
				)
				(justify mirror)
			)
		)
		(property "MPN" "CR0402-FX-1022GLF"
			(at 0 0 0)
			(layer "B.Fab")
			(hide yes)
			(effects
				(font
					(size 1 1)
					(thickness 0.15)
				)
				(justify mirror)
			)
		)
		(property "Manufacturer" "Bourns"
			(at 0 0 0)
			(layer "B.Fab")
			(hide yes)
			(effects
				(font
					(size 1 1)
					(thickness 0.15)
				)
				(justify mirror)
			)
		)
		(property "Tolerance" "1%"
			(at 0 0 0)
			(layer "B.Fab")
			(hide yes)
			(effects
				(font
					(size 1 1)
					(thickness 0.15)
				)
				(justify mirror)
			)
		)
		(property "Val" "10k2"
			(at 0 0 0)
			(layer "B.Fab")
			(hide yes)
			(effects
				(font
					(size 1 1)
					(thickness 0.15)
				)
				(justify mirror)
			)
		)
		(sheetname "Ethernet")
		(sheetfile "ethernet.kicad_sch")
		(attr smd)
		(fp_rect
			(start -0.93 0.47)
			(end 0.93 -0.47)
			(stroke
				(width 0.05)
				(type solid)
			)
			(fill no)
			(layer "B.CrtYd")
		)
		(fp_rect
			(start -0.5 0.25)
			(end 0.5 -0.25)
			(stroke
				(width 0.15)
				(type solid)
			)
			(fill no)
			(layer "B.Fab")
		)
		(pad "1" smd roundrect
			(at -0.485 0)
			(size 0.59 0.64)
			(layers "B.Cu" "B.Mask" "B.Paste")
			(roundrect_rratio 0.25)
			(net 12 "LED_LINK")
			(pintype "passive")
		)
		(pad "2" smd roundrect
			(at 0.485 0)
			(size 0.59 0.64)
			(layers "B.Cu" "B.Mask" "B.Paste")
			(roundrect_rratio 0.25)
			(net 459 "3V3_SYS")
			(pintype "passive")
		)
	)
	(footprint "antmicro-footprints:FB_0603_1608Metric"
		(layer "B.Cu")
		(at 200.486328 106.53 -90)
		(property "Reference" "FB6"
			(at -1.03 -1.613672 90)
			(layer "B.SilkS")
			(effects
				(font
					(size 0.7 0.7)
					(thickness 0.15)
				)
				(justify left bottom mirror)
			)
		)
		(property "Value" "FB_120Z_2A_0603"
			(at 0 -1.5 90)
			(layer "B.Fab")
			(effects
				(font
					(size 0.7 0.7)
					(thickness 0.15)
				)
				(justify left bottom mirror)
			)
		)
		(property "Description" "Ferrite Beads WE-TMSB Suppression 240Ohm 200mA "
			(at 0 0 270)
			(layer "F.Fab")
			(hide yes)
			(effects
				(font
					(size 1.27 1.27)
					(thickness 0.15)
				)
			)
		)
		(property "Author" "Antmicro"
			(at 93.956328 307.016328 0)
			(layer "B.Fab")
			(hide yes)
			(effects
				(font
					(size 1 1)
					(thickness 0.15)
				)
				(justify mirror)
			)
		)
		(property "License" "Apache-2.0"
			(at 93.956328 307.016328 0)
			(layer "B.Fab")
			(hide yes)
			(effects
				(font
					(size 1 1)
					(thickness 0.15)
				)
				(justify mirror)
			)
		)
		(property "MPN" "BLM18PG121SN1D"
			(at 93.956328 307.016328 0)
			(layer "B.Fab")
			(hide yes)
			(effects
				(font
					(size 1 1)
					(thickness 0.15)
				)
				(justify mirror)
			)
		)
		(property "Manufacturer" "Murata"
			(at 93.956328 307.016328 0)
			(layer "B.Fab")
			(hide yes)
			(effects
				(font
					(size 1 1)
					(thickness 0.15)
				)
				(justify mirror)
			)
		)
		(sheetname "Ethernet")
		(sheetfile "ethernet.kicad_sch")
		(attr smd)
		(fp_line
			(start -0.196 0.408)
			(end 0.193 0.408)
			(stroke
				(width 0.15)
				(type solid)
			)
			(layer "B.SilkS")
		)
		(fp_line
			(start -0.196 -0.406)
			(end 0.193 -0.406)
			(stroke
				(width 0.15)
				(type solid)
			)
			(layer "B.SilkS")
		)
		(fp_rect
			(start -1.3 0.6)
			(end 1.3 -0.6)
			(stroke
				(width 0.05)
				(type solid)
			)
			(fill no)
			(layer "B.CrtYd")
		)
		(fp_line
			(start 0.8 0.408)
			(end -0.803 0.408)
			(stroke
				(width 0.15)
				(type solid)
			)
			(layer "B.Fab")
		)
		(fp_line
			(start 0.8 0.408)
			(end 0.8 -0.406)
			(stroke
				(width 0.15)
				(type solid)
			)
			(layer "B.Fab")
		)
		(fp_line
			(start -0.803 -0.406)
			(end -0.803 0.408)
			(stroke
				(width 0.15)
				(type solid)
			)
			(layer "B.Fab")
		)
		(fp_line
			(start 0.8 -0.406)
			(end -0.803 -0.406)
			(stroke
				(width 0.15)
				(type solid)
			)
			(layer "B.Fab")
		)
		(pad "1" smd roundrect
			(at -0.891 0 270)
			(size 0.762 1.09)
			(layers "B.Cu" "B.Mask" "B.Paste")
			(roundrect_rratio 0.15)
			(net 602 "1V2_SYS")
			(pintype "passive")
		)
		(pad "2" smd roundrect
			(at 0.888 0 270)
			(size 0.762 1.09)
			(layers "B.Cu" "B.Mask" "B.Paste")
			(roundrect_rratio 0.15)
			(net 529 "/Ethernet/AVDDL")
			(pintype "passive")
		)
	)
	(footprint "antmicro-footprints:C_0402_1005Metric"
		(layer "B.Cu")
		(at 201.086328 108.774306 -90)
		(descr "Capacitor SMD 0402")
		(tags "capacitor SMD 0402")
		(property "Reference" "C112"
			(at 0.810694 -0.413672 90)
			(layer "B.SilkS")
			(effects
				(font
					(size 0.7 0.7)
					(thickness 0.15)
				)
				(justify left bottom mirror)
			)
		)
		(property "Value" "C_10n_0402"
			(at 0 -1.4 90)
			(layer "B.Fab")
			(effects
				(font
					(size 0.7 0.7)
					(thickness 0.15)
				)
				(justify left bottom mirror)
			)
		)
		(property "Description" " "
			(at 0 0 270)
			(layer "F.Fab")
			(hide yes)
			(effects
				(font
					(size 1.27 1.27)
					(thickness 0.15)
				)
			)
		)
		(property "Author" "Antmicro"
			(at 92.312022 309.860634 0)
			(layer "B.Fab")
			(hide yes)
			(effects
				(font
					(size 1 1)
					(thickness 0.15)
				)
				(justify mirror)
			)
		)
		(property "Dielectric" "X7R"
			(at 92.312022 309.860634 0)
			(layer "B.Fab")
			(hide yes)
			(effects
				(font
					(size 1 1)
					(thickness 0.15)
				)
				(justify mirror)
			)
		)
		(property "License" "Apache-2.0"
			(at 92.312022 309.860634 0)
			(layer "B.Fab")
			(hide yes)
			(effects
				(font
					(size 1 1)
					(thickness 0.15)
				)
				(justify mirror)
			)
		)
		(property "MPN" "GRM155R71H103KA88D"
			(at 92.312022 309.860634 0)
			(layer "B.Fab")
			(hide yes)
			(effects
				(font
					(size 1 1)
					(thickness 0.15)
				)
				(justify mirror)
			)
		)
		(property "Manufacturer" "Murata"
			(at 92.312022 309.860634 0)
			(layer "B.Fab")
			(hide yes)
			(effects
				(font
					(size 1 1)
					(thickness 0.15)
				)
				(justify mirror)
			)
		)
		(property "Val" "10n"
			(at 92.312022 309.860634 0)
			(layer "B.Fab")
			(hide yes)
			(effects
				(font
					(size 1 1)
					(thickness 0.15)
				)
				(justify mirror)
			)
		)
		(property "Voltage" "50V"
			(at 92.312022 309.860634 0)
			(layer "B.Fab")
			(hide yes)
			(effects
				(font
					(size 1 1)
					(thickness 0.15)
				)
				(justify mirror)
			)
		)
		(sheetname "Ethernet")
		(sheetfile "ethernet.kicad_sch")
		(attr smd)
		(fp_rect
			(start -0.94 0.47)
			(end 0.94 -0.47)
			(stroke
				(width 0.05)
				(type solid)
			)
			(fill no)
			(layer "B.CrtYd")
		)
		(fp_rect
			(start -0.499 0.249)
			(end 0.499 -0.249)
			(stroke
				(width 0.15)
				(type solid)
			)
			(fill no)
			(layer "B.Fab")
		)
		(pad "1" smd roundrect
			(at -0.484 0 270)
			(size 0.59 0.64)
			(layers "B.Cu" "B.Mask" "B.Paste")
			(roundrect_rratio 0.25)
			(net 529 "/Ethernet/AVDDL")
			(pintype "passive")
		)
		(pad "2" smd roundrect
			(at 0.484 0 270)
			(size 0.59 0.64)
			(layers "B.Cu" "B.Mask" "B.Paste")
			(roundrect_rratio 0.25)
			(net 5 "GND")
			(pintype "passive")
		)
	)
	(footprint "antmicro-footprints:C_0402_1005Metric"
		(layer "B.Cu")
		(at 201.586328 100.020008 -90)
		(descr "Capacitor SMD 0402")
		(tags "capacitor SMD 0402")
		(property "Reference" "C104"
			(at -1.820008 -6.613672 90)
			(layer "B.SilkS")
			(effects
				(font
					(size 0.7 0.7)
					(thickness 0.15)
				)
				(justify left bottom mirror)
			)
		)
		(property "Value" "C_470n_0402"
			(at 0 -1.4 90)
			(layer "B.Fab")
			(effects
				(font
					(size 0.7 0.7)
					(thickness 0.15)
				)
				(justify left bottom mirror)
			)
		)
		(property "Description" " "
			(at 0 0 270)
			(layer "F.Fab")
			(hide yes)
			(effects
				(font
					(size 1.27 1.27)
					(thickness 0.15)
				)
			)
		)
		(property "Author" "Antmicro"
			(at 101.56632 301.606336 0)
			(layer "B.Fab")
			(hide yes)
			(effects
				(font
					(size 1 1)
					(thickness 0.15)
				)
				(justify mirror)
			)
		)
		(property "Dielectric" ""
			(at 101.56632 301.606336 0)
			(layer "B.Fab")
			(hide yes)
			(effects
				(font
					(size 1 1)
					(thickness 0.15)
				)
				(justify mirror)
			)
		)
		(property "License" "Apache-2.0"
			(at 101.56632 301.606336 0)
			(layer "B.Fab")
			(hide yes)
			(effects
				(font
					(size 1 1)
					(thickness 0.15)
				)
				(justify mirror)
			)
		)
		(property "MPN" "C1005X5R1E474M050BB"
			(at 101.56632 301.606336 0)
			(layer "B.Fab")
			(hide yes)
			(effects
				(font
					(size 1 1)
					(thickness 0.15)
				)
				(justify mirror)
			)
		)
		(property "Manufacturer" "TDK"
			(at 101.56632 301.606336 0)
			(layer "B.Fab")
			(hide yes)
			(effects
				(font
					(size 1 1)
					(thickness 0.15)
				)
				(justify mirror)
			)
		)
		(property "Val" "470n"
			(at 101.56632 301.606336 0)
			(layer "B.Fab")
			(hide yes)
			(effects
				(font
					(size 1 1)
					(thickness 0.15)
				)
				(justify mirror)
			)
		)
		(property "Voltage" ""
			(at 101.56632 301.606336 0)
			(layer "B.Fab")
			(hide yes)
			(effects
				(font
					(size 1 1)
					(thickness 0.15)
				)
				(justify mirror)
			)
		)
		(sheetname "Ethernet")
		(sheetfile "ethernet.kicad_sch")
		(attr smd)
		(fp_rect
			(start -0.94 0.47)
			(end 0.94 -0.47)
			(stroke
				(width 0.05)
				(type solid)
			)
			(fill no)
			(layer "B.CrtYd")
		)
		(fp_rect
			(start -0.499 0.249)
			(end 0.499 -0.249)
			(stroke
				(width 0.15)
				(type solid)
			)
			(fill no)
			(layer "B.Fab")
		)
		(pad "1" smd roundrect
			(at -0.484 0 270)
			(size 0.59 0.64)
			(layers "B.Cu" "B.Mask" "B.Paste")
			(roundrect_rratio 0.25)
			(net 602 "1V2_SYS")
			(pintype "passive")
		)
		(pad "2" smd roundrect
			(at 0.484 0 270)
			(size 0.59 0.64)
			(layers "B.Cu" "B.Mask" "B.Paste")
			(roundrect_rratio 0.25)
			(net 5 "GND")
			(pintype "passive")
		)
	)
)
